# BASEBOARD_FAB2 (Tioga Pass) — schematic netlist excerpt (pin names and nets, part order shuffled) for the footprints in the layout excerpt that follows; sources: Cadence DE-HDL packaged netlist, KiCad conversion of Wiwynn_Tioga_Pass_MB.brd

R1D21  RES  4.75K 1% CHIP  pkg 0402  page 200 : A = P3V3_STBY ; B = FM_OC_DETECT_EN
R9W13  RES  20.0 1% CHIP  pkg 0402  page 248 : A = SMB_PEHPCPU0_STBY_LVC3_R_SDA ; B = SMB_PEHPCPU0_STBY_LVC3_SDA
C6U8  CAP  10UF 16V 10% X6S  pkg 0805  page 233 : A = VR_FET_SW_P12V_STBY_PVPP_GHJ ; B = GND

(kicad_pcb
	(version 20260206)
	(generator "pcbnew")
	(generator_version "10.0")
	(general
		(thickness 1.6)
		(legacy_teardrops no)
	)
	(paper "A4")
	(title_block
		(title "Wiwynn_Tioga_Pass_MB.brd")
		(comment 1 "Tioga Pass / footprints 1484-1486 of 4770")
	)
	(layers
		(0 "F.Cu" signal "TOP")
		(4 "In1.Cu" signal "L2GND")
		(6 "In2.Cu" signal "L3")
		(8 "In3.Cu" signal "L4GND")
		(10 "In4.Cu" signal "L5")
		(12 "In5.Cu" signal "L6GND")
		(14 "In6.Cu" signal "L7VCC")
		(16 "In7.Cu" signal "L8VCC")
		(18 "In8.Cu" signal "L9GND")
		(20 "In9.Cu" signal "L10")
		(22 "In10.Cu" signal "L11GND")
		(24 "In11.Cu" signal "L12")
		(26 "In12.Cu" signal "L13GND")
		(2 "B.Cu" signal "BOTTOM")
		(9 "F.Adhes" user "F.Adhesive")
		(11 "B.Adhes" user "B.Adhesive")
		(13 "F.Paste" user "Package Geometry/Pastemask Top")
		(15 "B.Paste" user "Package Geometry/Pastemask Bottom")
		(5 "F.SilkS" user "Ref Des/Silkscreen Top")
		(7 "B.SilkS" user "Ref Des/Silkscreen Bottom")
		(1 "F.Mask" user "Board Geometry/Soldermask Top")
		(3 "B.Mask" user "Board Geometry/Soldermask Bottom")
		(17 "Dwgs.User" user "User.Drawings")
		(19 "Cmts.User" user "User.Comments")
		(21 "Eco1.User" user "User.Eco1")
		(23 "Eco2.User" user "User.Eco2")
		(25 "Edge.Cuts" user "Board Geometry/Outline")
		(27 "Margin" user)
		(31 "F.CrtYd" user "Package Geometry/Place Bound Top")
		(29 "B.CrtYd" user "Package Geometry/Place Bound Bottom")
		(35 "F.Fab" user "Ref Des/Assembly Top")
		(33 "B.Fab" user "Ref Des/Assembly Bottom")
	)
	(footprint ""
		(layer "F.Cu")
		(at 183.167274 -10.91057 90)
		(property "Reference" "C6U8"
			(at 1.47828 0.78994 0)
			(unlocked yes)
			(layer "F.SilkS")
			(effects
				(font
					(size 0.4064 0.254)
					(thickness 0.1524)
				)
			)
		)
		(property "Value" ""
			(at 0 0 90)
			(layer "F.Fab")
			(effects
				(font
					(size 1.27 1.27)
				)
			)
		)
		(duplicate_pad_numbers_are_jumpers no)
		(fp_poly
			(pts
				(xy -0.7239 -0.2159) (xy 0.7239 -0.2159) (xy 0.7239 1.9939) (xy -0.7239 1.9939)
			)
			(stroke
				(width 0)
				(type default)
			)
			(fill no)
			(layer "F.CrtYd")
		)
		(fp_line
			(start 0.7239 -0.2159)
			(end -0.7239 -0.2159)
			(stroke
				(width 0.1)
				(type default)
			)
			(layer "F.Fab")
		)
		(fp_line
			(start -0.7239 -0.2159)
			(end -0.7239 1.9939)
			(stroke
				(width 0.1)
				(type default)
			)
			(layer "F.Fab")
		)
		(fp_line
			(start 0.7239 1.9939)
			(end 0.7239 -0.2159)
			(stroke
				(width 0.1)
				(type default)
			)
			(layer "F.Fab")
		)
		(fp_line
			(start -0.7239 1.9939)
			(end 0.7239 1.9939)
			(stroke
				(width 0.1)
				(type default)
			)
			(layer "F.Fab")
		)
		(pad "1" smd rect
			(at 0 0 90)
			(size 1.27 1.016)
			(layers "F.Cu" "F.Mask" "F.Paste")
			(net "VR_FET_SW_P12V_STBY_PVPP_GHJ")
		)
		(pad "2" smd rect
			(at 0 1.778 90)
			(size 1.27 1.016)
			(layers "F.Cu" "F.Mask" "F.Paste")
			(net "GND")
		)
		(zone
			(layer "F.Cu")
			(hatch none 0.5)
			(connect_pads
				(clearance 0)
			)
			(min_thickness 0.25)
			(keepout
				(tracks not_allowed)
				(vias allowed)
				(pads allowed)
				(copperpour not_allowed)
				(footprints allowed)
			)
			(placement
				(enabled no)
				(sheetname "")
			)
			(fill
				(thermal_gap 0.5)
				(thermal_bridge_width 0.5)
				(island_removal_mode 0)
			)
			(polygon
				(pts
					(xy 183.675274 -10.27557) (xy 183.675274 -11.54557) (xy 184.437274 -11.54557) (xy 184.437274 -10.27557)
				)
			)
		)
	)
	(footprint ""
		(layer "F.Cu")
		(at 25.4 -81.026 180)
		(property "Reference" "R1D21"
			(at 0 0 180)
			(layer "F.SilkS")
			(hide yes)
			(effects
				(font
					(size 1.27 1.27)
				)
			)
		)
		(property "Value" ""
			(at 0 0 180)
			(layer "F.Fab")
			(effects
				(font
					(size 1.27 1.27)
				)
			)
		)
		(duplicate_pad_numbers_are_jumpers no)
		(fp_poly
			(pts
				(xy -0.2794 -0.1016) (xy 0.2794 -0.1016) (xy 0.2794 0.9906) (xy -0.2794 0.9906)
			)
			(stroke
				(width 0)
				(type default)
			)
			(fill no)
			(layer "F.CrtYd")
		)
		(fp_line
			(start 0.2794 0.9906)
			(end 0.2794 -0.1016)
			(stroke
				(width 0.1)
				(type default)
			)
			(layer "F.Fab")
		)
		(fp_line
			(start 0.2794 -0.1016)
			(end -0.2794 -0.1016)
			(stroke
				(width 0.1)
				(type default)
			)
			(layer "F.Fab")
		)
		(fp_line
			(start -0.2794 0.9906)
			(end 0.2794 0.9906)
			(stroke
				(width 0.1)
				(type default)
			)
			(layer "F.Fab")
		)
		(fp_line
			(start -0.2794 -0.1016)
			(end -0.2794 0.9906)
			(stroke
				(width 0.1)
				(type default)
			)
			(layer "F.Fab")
		)
		(pad "1" smd rect
			(at 0 0 180)
			(size 0.508 0.508)
			(layers "F.Cu" "F.Mask" "F.Paste")
			(net "P3V3_STBY")
		)
		(pad "2" smd rect
			(at 0 0.889 180)
			(size 0.508 0.508)
			(layers "F.Cu" "F.Mask" "F.Paste")
			(net "FM_OC_DETECT_EN")
		)
		(zone
			(layer "F.Cu")
			(hatch none 0.5)
			(connect_pads
				(clearance 0)
			)
			(min_thickness 0.25)
			(keepout
				(tracks not_allowed)
				(vias allowed)
				(pads allowed)
				(copperpour not_allowed)
				(footprints allowed)
			)
			(placement
				(enabled no)
				(sheetname "")
			)
			(fill
				(thermal_gap 0.5)
				(thermal_bridge_width 0.5)
				(island_removal_mode 0)
			)
			(polygon
				(pts
					(xy 25.654 -81.661) (xy 25.146 -81.661) (xy 25.146 -81.28) (xy 25.654 -81.28)
				)
			)
		)
		(zone
			(layer "F.Cu")
			(hatch none 0.5)
			(connect_pads
				(clearance 0)
			)
			(min_thickness 0.25)
			(keepout
				(tracks allowed)
				(vias not_allowed)
				(pads allowed)
				(copperpour not_allowed)
				(footprints allowed)
			)
			(placement
				(enabled no)
				(sheetname "")
			)
			(fill
				(thermal_gap 0.5)
				(thermal_bridge_width 0.5)
				(island_removal_mode 0)
			)
			(polygon
				(pts
					(xy 25.654 -81.28) (xy 25.146 -81.28) (xy 25.146 -81.661) (xy 25.654 -81.661)
				)
			)
		)
	)
	(footprint ""
		(layer "F.Cu")
		(at 421.386 -113.8555 180)
		(property "Reference" "R9W13"
			(at -0.8382 -0.67818 180)
			(unlocked yes)
			(layer "F.SilkS")
			(effects
				(font
					(size 0.4064 0.254)
					(thickness 0.1524)
				)
				(justify left)
			)
		)
		(property "Value" ""
			(at 0 0 180)
			(layer "F.Fab")
			(effects
				(font
					(size 1.27 1.27)
				)
			)
		)
		(duplicate_pad_numbers_are_jumpers no)
		(fp_poly
			(pts
				(xy -0.2794 -0.1016) (xy 0.2794 -0.1016) (xy 0.2794 0.9906) (xy -0.2794 0.9906)
			)
			(stroke
				(width 0)
				(type default)
			)
			(fill no)
			(layer "F.CrtYd")
		)
		(fp_line
			(start 0.2794 0.9906)
			(end 0.2794 -0.1016)
			(stroke
				(width 0.1)
				(type default)
			)
			(layer "F.Fab")
		)
		(fp_line
			(start 0.2794 -0.1016)
			(end -0.2794 -0.1016)
			(stroke
				(width 0.1)
				(type default)
			)
			(layer "F.Fab")
		)
		(fp_line
			(start -0.2794 0.9906)
			(end 0.2794 0.9906)
			(stroke
				(width 0.1)
				(type default)
			)
			(layer "F.Fab")
		)
		(fp_line
			(start -0.2794 -0.1016)
			(end -0.2794 0.9906)
			(stroke
				(width 0.1)
				(type default)
			)
			(layer "F.Fab")
		)
		(pad "1" smd rect
			(at 0 0 180)
			(size 0.508 0.508)
			(layers "F.Cu" "F.Mask" "F.Paste")
			(net "SMB_PEHPCPU0_STBY_LVC3_R_SDA")
		)
		(pad "2" smd rect
			(at 0 0.889 180)
			(size 0.508 0.508)
			(layers "F.Cu" "F.Mask" "F.Paste")
			(net "SMB_PEHPCPU0_STBY_LVC3_SDA")
		)
		(zone
			(layer "F.Cu")
			(hatch none 0.5)
			(connect_pads
				(clearance 0)
			)
			(min_thickness 0.25)
			(keepout
				(tracks not_allowed)
				(vias allowed)
				(pads allowed)
				(copperpour not_allowed)
				(footprints allowed)
			)
			(placement
				(enabled no)
				(sheetname "")
			)
			(fill
				(thermal_gap 0.5)
				(thermal_bridge_width 0.5)
				(island_removal_mode 0)
			)
			(polygon
				(pts
					(xy 421.64 -114.4905) (xy 421.132 -114.4905) (xy 421.132 -114.1095) (xy 421.64 -114.1095)
				)
			)
		)
		(zone
			(layer "F.Cu")
			(hatch none 0.5)
			(connect_pads
				(clearance 0)
			)
			(min_thickness 0.25)
			(keepout
				(tracks allowed)
				(vias not_allowed)
				(pads allowed)
				(copperpour not_allowed)
				(footprints allowed)
			)
			(placement
				(enabled no)
				(sheetname "")
			)
			(fill
				(thermal_gap 0.5)
				(thermal_bridge_width 0.5)
				(island_removal_mode 0)
			)
			(polygon
				(pts
					(xy 421.64 -114.1095) (xy 421.132 -114.1095) (xy 421.132 -114.4905) (xy 421.64 -114.4905)
				)
			)
		)
	)
)
